(kicad_pcb
	(version 20260206)
	(generator "pcbnew")
	(generator_version "10.0")
	(general
		(thickness 1.6)
		(legacy_teardrops no)
	)
	(paper "A4")
	(title_block
		(title "01162023_DA0F0TEBIF0_F0T_Expander_BD_F_brd_V02_OCP.brd")
		(comment 1 "Grand Teton / footprints 6618-6618 of 9728")
	)
	(layers
		(0 "F.Cu" signal "TOP")
		(4 "In1.Cu" signal "GND")
		(6 "In2.Cu" signal "VCC")
		(8 "In3.Cu" signal "VCC1")
		(10 "In4.Cu" signal "GND1")
		(12 "In5.Cu" signal "IN1")
		(14 "In6.Cu" signal "GND2")
		(16 "In7.Cu" signal "IN2")
		(18 "In8.Cu" signal "GND3")
		(20 "In9.Cu" signal "IN3")
		(22 "In10.Cu" signal "GND4")
		(24 "In11.Cu" signal "IN4")
		(26 "In12.Cu" signal "GND5")
		(28 "In13.Cu" signal "IN5")
		(30 "In14.Cu" signal "GND6")
		(32 "In15.Cu" signal "IN6")
		(34 "In16.Cu" signal "GND7")
		(2 "B.Cu" signal "BOTTOM")
		(9 "F.Adhes" user "F.Adhesive")
		(11 "B.Adhes" user "B.Adhesive")
		(13 "F.Paste" user "Package Geometry/Pastemask Top")
		(15 "B.Paste" user "Package Geometry/Pastemask Bottom")
		(5 "F.SilkS" user "Ref Des/Silkscreen Top")
		(7 "B.SilkS" user "Ref Des/Silkscreen Bottom")
		(1 "F.Mask" user "Board Geometry/Soldermask Top")
		(3 "B.Mask" user "Board Geometry/Soldermask Bottom")
		(17 "Dwgs.User" user "User.Drawings")
		(19 "Cmts.User" user "User.Comments")
		(21 "Eco1.User" user "User.Eco1")
		(23 "Eco2.User" user "User.Eco2")
		(25 "Edge.Cuts" user "Board Geometry/Outline")
		(27 "Margin" user)
		(31 "F.CrtYd" user "Package Geometry/Place Bound Top")
		(29 "B.CrtYd" user "Package Geometry/Place Bound Bottom")
		(35 "F.Fab" user "Ref Des/Assembly Top")
		(33 "B.Fab" user "Ref Des/Assembly Bottom")
	)
	(footprint ""
		(layer "F.Cu")
		(at 181.728872 -356.244906 90)
		(property "Reference" "C382"
			(at 0 0 90)
			(layer "F.SilkS")
			(hide yes)
			(effects
				(font
					(size 1.27 1.27)
				)
			)
		)
		(property "Value" ""
			(at 0 0 90)
			(layer "F.Fab")
			(effects
				(font
					(size 1.27 1.27)
				)
			)
		)
		(duplicate_pad_numbers_are_jumpers no)
		(fp_line
			(start 0.299974 -0.150114)
			(end 0.299974 0.150114)
			(stroke
				(width 0.1)
				(type default)
			)
			(layer "F.Fab")
		)
		(fp_line
			(start -0.299974 -0.150114)
			(end 0.299974 -0.150114)
			(stroke
				(width 0.1)
				(type default)
			)
			(layer "F.Fab")
		)
		(fp_line
			(start 0.299974 0.150114)
			(end -0.299974 0.150114)
			(stroke
				(width 0.1)
				(type default)
			)
			(layer "F.Fab")
		)
		(fp_line
			(start -0.299974 0.150114)
			(end -0.299974 -0.150114)
			(stroke
				(width 0.1)
				(type default)
			)
			(layer "F.Fab")
		)
		(pad "1" smd rect
			(at -0.2667 0 90)
			(size 0.3048 0.381)
			(layers "F.Cu" "F.Mask" "F.Paste")
			(net "P5E_PEX1_STN7_TX_DP<122>")
		)
		(pad "2" smd rect
			(at 0.2667 0 90)
			(size 0.3048 0.381)
			(layers "F.Cu" "F.Mask" "F.Paste")
			(net "P5E_PEX1_STN7_TX_C_DP<122>")
		)
	)
)
